# BASEBOARD_FAB2 (Tioga Pass) — schematic netlist excerpt (pin names and nets, part order shuffled) for the footprints in the layout excerpt that follows; sources: Cadence DE-HDL packaged netlist, KiCad conversion of Wiwynn_Tioga_Pass_MB.brd

XLU2  SOCKET_P_MECH_A  PLASTIC  pkg LEFT  page 55

(kicad_pcb
	(version 20260206)
	(generator "pcbnew")
	(generator_version "10.0")
	(general
		(thickness 1.6)
		(legacy_teardrops no)
	)
	(paper "A4")
	(title_block
		(title "Wiwynn_Tioga_Pass_MB.brd")
		(comment 1 "Tioga Pass / footprints 1447-1447 of 4770")
	)
	(layers
		(0 "F.Cu" signal "TOP")
		(4 "In1.Cu" signal "L2GND")
		(6 "In2.Cu" signal "L3")
		(8 "In3.Cu" signal "L4GND")
		(10 "In4.Cu" signal "L5")
		(12 "In5.Cu" signal "L6GND")
		(14 "In6.Cu" signal "L7VCC")
		(16 "In7.Cu" signal "L8VCC")
		(18 "In8.Cu" signal "L9GND")
		(20 "In9.Cu" signal "L10")
		(22 "In10.Cu" signal "L11GND")
		(24 "In11.Cu" signal "L12")
		(26 "In12.Cu" signal "L13GND")
		(2 "B.Cu" signal "BOTTOM")
		(9 "F.Adhes" user "F.Adhesive")
		(11 "B.Adhes" user "B.Adhesive")
		(13 "F.Paste" user "Package Geometry/Pastemask Top")
		(15 "B.Paste" user "Package Geometry/Pastemask Bottom")
		(5 "F.SilkS" user "Ref Des/Silkscreen Top")
		(7 "B.SilkS" user "Ref Des/Silkscreen Bottom")
		(1 "F.Mask" user "Board Geometry/Soldermask Top")
		(3 "B.Mask" user "Board Geometry/Soldermask Bottom")
		(17 "Dwgs.User" user "User.Drawings")
		(19 "Cmts.User" user "User.Comments")
		(21 "Eco1.User" user "User.Eco1")
		(23 "Eco2.User" user "User.Eco2")
		(25 "Edge.Cuts" user "Board Geometry/Outline")
		(27 "Margin" user)
		(31 "F.CrtYd" user "Package Geometry/Place Bound Top")
		(29 "B.CrtYd" user "Package Geometry/Place Bound Bottom")
		(35 "F.Fab" user "Ref Des/Assembly Top")
		(33 "B.Fab" user "Ref Des/Assembly Bottom")
	)
	(footprint ""
		(layer "F.Cu")
		(at 85.777578 -75.65009 180)
		(property "Reference" "XLU2"
			(at 22.150578 34.43224 0)
			(unlocked yes)
			(layer "F.SilkS")
			(effects
				(font
					(size 0.7874 0.5842)
					(thickness 0.1524)
				)
				(justify left)
			)
		)
		(property "Value" ""
			(at 0 0 180)
			(layer "F.Fab")
			(effects
				(font
					(size 1.27 1.27)
				)
			)
		)
		(duplicate_pad_numbers_are_jumpers no)
		(fp_line
			(start 21.77796 31.949898)
			(end 21.77796 8.899906)
			(stroke
				(width 0.1524)
				(type default)
			)
			(layer "F.SilkS")
		)
		(fp_line
			(start 21.77796 8.899906)
			(end 18.278094 5.40004)
			(stroke
				(width 0.1524)
				(type default)
			)
			(layer "F.SilkS")
		)
		(fp_line
			(start 21.77796 -7.100062)
			(end 21.77796 -30.150054)
			(stroke
				(width 0.1524)
				(type default)
			)
			(layer "F.SilkS")
		)
		(fp_line
			(start 21.77796 -30.150054)
			(end 14.777974 -30.150054)
			(stroke
				(width 0.1524)
				(type default)
			)
			(layer "F.SilkS")
		)
		(fp_line
			(start 18.278094 5.40004)
			(end 18.278094 3.899916)
			(stroke
				(width 0.1524)
				(type default)
			)
			(layer "F.SilkS")
		)
		(fp_line
			(start 18.278094 3.899916)
			(end 17.777968 3.899916)
			(stroke
				(width 0.1524)
				(type default)
			)
			(layer "F.SilkS")
		)
		(fp_line
			(start 18.278094 -2.100072)
			(end 18.278094 -3.599942)
			(stroke
				(width 0.1524)
				(type default)
			)
			(layer "F.SilkS")
		)
		(fp_line
			(start 18.278094 -3.599942)
			(end 21.77796 -7.100062)
			(stroke
				(width 0.1524)
				(type default)
			)
			(layer "F.SilkS")
		)
		(fp_line
			(start 17.777968 3.899916)
			(end 17.777968 -2.100072)
			(stroke
				(width 0.1524)
				(type default)
			)
			(layer "F.SilkS")
		)
		(fp_line
			(start 17.777968 -2.100072)
			(end 18.278094 -2.100072)
			(stroke
				(width 0.1524)
				(type default)
			)
			(layer "F.SilkS")
		)
		(fp_line
			(start 14.777974 31.949898)
			(end 21.77796 31.949898)
			(stroke
				(width 0.1524)
				(type default)
			)
			(layer "F.SilkS")
		)
		(fp_line
			(start 14.777974 29.399992)
			(end 14.777974 31.949898)
			(stroke
				(width 0.1524)
				(type default)
			)
			(layer "F.SilkS")
		)
		(fp_line
			(start 14.777974 -27.599894)
			(end -17.622012 -27.599894)
			(stroke
				(width 0.1524)
				(type default)
			)
			(layer "F.SilkS")
		)
		(fp_line
			(start 14.777974 -30.150054)
			(end 14.777974 -27.599894)
			(stroke
				(width 0.1524)
				(type default)
			)
			(layer "F.SilkS")
		)
		(fp_line
			(start -6.171946 6.690106)
			(end -12.761976 10.649966)
			(stroke
				(width 0.1524)
				(type default)
			)
			(layer "F.SilkS")
		)
		(fp_line
			(start -6.171946 -4.890008)
			(end -6.171946 6.690106)
			(stroke
				(width 0.1524)
				(type default)
			)
			(layer "F.SilkS")
		)
		(fp_line
			(start -12.761976 10.649966)
			(end -19.221958 10.649966)
			(stroke
				(width 0.1524)
				(type default)
			)
			(layer "F.SilkS")
		)
		(fp_line
			(start -12.761976 -8.850122)
			(end -6.171946 -4.890008)
			(stroke
				(width 0.1524)
				(type default)
			)
			(layer "F.SilkS")
		)
		(fp_line
			(start -17.622012 30.39999)
			(end -17.622012 29.399992)
			(stroke
				(width 0.1524)
				(type default)
			)
			(layer "F.SilkS")
		)
		(fp_line
			(start -17.622012 29.399992)
			(end 14.777974 29.399992)
			(stroke
				(width 0.1524)
				(type default)
			)
			(layer "F.SilkS")
		)
		(fp_line
			(start -17.622012 -27.599894)
			(end -17.622012 -28.599892)
			(stroke
				(width 0.1524)
				(type default)
			)
			(layer "F.SilkS")
		)
		(fp_line
			(start -17.622012 -28.599892)
			(end -18.62201 -28.599892)
			(stroke
				(width 0.1524)
				(type default)
			)
			(layer "F.SilkS")
		)
		(fp_line
			(start -18.62201 30.39999)
			(end -17.622012 30.39999)
			(stroke
				(width 0.1524)
				(type default)
			)
			(layer "F.SilkS")
		)
		(fp_line
			(start -18.62201 29.399992)
			(end -18.62201 30.39999)
			(stroke
				(width 0.1524)
				(type default)
			)
			(layer "F.SilkS")
		)
		(fp_line
			(start -18.62201 -8.850122)
			(end -12.761976 -8.850122)
			(stroke
				(width 0.1524)
				(type default)
			)
			(layer "F.SilkS")
		)
		(fp_line
			(start -18.62201 -28.599892)
			(end -18.62201 -8.850122)
			(stroke
				(width 0.1524)
				(type default)
			)
			(layer "F.SilkS")
		)
		(fp_line
			(start -19.221958 29.399992)
			(end -18.62201 29.399992)
			(stroke
				(width 0.1524)
				(type default)
			)
			(layer "F.SilkS")
		)
		(fp_line
			(start -19.221958 10.649966)
			(end -19.221958 29.399992)
			(stroke
				(width 0.1524)
				(type default)
			)
			(layer "F.SilkS")
		)
		(fp_poly
			(pts
				(xy 19.777964 -5.100066) (xy 19.777964 -22.649942) (xy 18.839434 -22.649942) (xy 18.839434 -27.410918)
				(xy 14.777974 -27.410918) (xy 14.777974 -30.150054) (xy 21.77796 -30.150054) (xy 21.77796 -7.100062)
			)
			(stroke
				(width 0)
				(type default)
			)
			(fill no)
			(layer "F.CrtYd")
		)
		(fp_poly
			(pts
				(arc
					(start 19.777964 17.616678)
					(mid 20.051978 16.900049)
					(end 19.777964 16.183356)
				)
				(xy 19.777964 6.89991) (xy 21.77796 8.899906) (xy 21.77796 31.949898) (xy 14.777974 31.949898) (xy 14.777974 29.211016)
				(xy 18.839434 29.211016) (xy 18.839434 24.449786) (xy 19.777964 24.449786)
			)
			(stroke
				(width 0)
				(type default)
			)
			(fill no)
			(layer "F.CrtYd")
		)
		(fp_line
			(start 21.77796 31.949898)
			(end 14.777974 31.949898)
			(stroke
				(width 0.1)
				(type default)
			)
			(layer "F.Fab")
		)
		(fp_line
			(start 21.77796 8.899906)
			(end 21.77796 31.949898)
			(stroke
				(width 0.1)
				(type default)
			)
			(layer "F.Fab")
		)
		(fp_line
			(start 21.77796 -7.100062)
			(end 19.777964 -5.100066)
			(stroke
				(width 0.1)
				(type default)
			)
			(layer "F.Fab")
		)
		(fp_line
			(start 21.77796 -30.150054)
			(end 21.77796 -7.100062)
			(stroke
				(width 0.1)
				(type default)
			)
			(layer "F.Fab")
		)
		(fp_line
			(start 19.777964 24.449786)
			(end 19.777964 22.078696)
			(stroke
				(width 0.1)
				(type default)
			)
			(layer "F.Fab")
		)
		(fp_line
			(start 19.777964 21.179028)
			(end 19.777964 17.616678)
			(stroke
				(width 0.1)
				(type default)
			)
			(layer "F.Fab")
		)
		(fp_line
			(start 19.777964 16.183356)
			(end 19.777964 6.89991)
			(stroke
				(width 0.1)
				(type default)
			)
			(layer "F.Fab")
		)
		(fp_line
			(start 19.777964 6.89991)
			(end 21.77796 8.899906)
			(stroke
				(width 0.1)
				(type default)
			)
			(layer "F.Fab")
		)
		(fp_line
			(start 19.777964 -5.100066)
			(end 19.777964 -22.649942)
			(stroke
				(width 0.1)
				(type default)
			)
			(layer "F.Fab")
		)
		(fp_line
			(start 19.777964 -22.649942)
			(end 18.839434 -22.649942)
			(stroke
				(width 0.1)
				(type default)
			)
			(layer "F.Fab")
		)
		(fp_line
			(start 18.839434 29.211016)
			(end 18.839434 24.449786)
			(stroke
				(width 0.1)
				(type default)
			)
			(layer "F.Fab")
		)
		(fp_line
			(start 18.839434 24.449786)
			(end 19.777964 24.449786)
			(stroke
				(width 0.1)
				(type default)
			)
			(layer "F.Fab")
		)
		(fp_line
			(start 18.839434 -22.649942)
			(end 18.839434 -27.410918)
			(stroke
				(width 0.1)
				(type default)
			)
			(layer "F.Fab")
		)
		(fp_line
			(start 18.839434 -27.410918)
			(end 14.777974 -27.410918)
			(stroke
				(width 0.1)
				(type default)
			)
			(layer "F.Fab")
		)
		(fp_line
			(start 14.777974 31.949898)
			(end 14.777974 29.211016)
			(stroke
				(width 0.1)
				(type default)
			)
			(layer "F.Fab")
		)
		(fp_line
			(start 14.777974 29.211016)
			(end 18.839434 29.211016)
			(stroke
				(width 0.1)
				(type default)
			)
			(layer "F.Fab")
		)
		(fp_line
			(start 14.777974 -27.410918)
			(end 14.777974 -30.150054)
			(stroke
				(width 0.1)
				(type default)
			)
			(layer "F.Fab")
		)
		(fp_line
			(start 14.777974 -30.150054)
			(end 21.77796 -30.150054)
			(stroke
				(width 0.1)
				(type default)
			)
			(layer "F.Fab")
		)
		(fp_arc
			(start 19.777964 22.078696)
			(mid 19.777668 21.628862)
			(end 19.777964 21.179028)
			(stroke
				(width 0.1)
				(type default)
			)
			(layer "F.Fab")
		)
		(fp_arc
			(start 19.777964 16.183356)
			(mid 20.051971 16.900015)
			(end 19.777964 17.616678)
			(stroke
				(width 0.1)
				(type default)
			)
			(layer "F.Fab")
		)
	)
)
